(kicad_pcb
	(version 20241229)
	(generator "pcbnew")
	(generator_version "9.0")
	(general
		(thickness 1.294)
		(legacy_teardrops no)
	)
	(paper "A3")
	(title_block
		(title "Kintex 410T devboard")
		(date "2024-04-03")
		(rev "1.1.2")
		(comment 9 "footprints 579-584 of 975")
	)
	(layers
		(0 "F.Cu" mixed)
		(4 "In1.Cu" power)
		(6 "In2.Cu" power)
		(8 "In3.Cu" mixed)
		(10 "In4.Cu" power)
		(12 "In5.Cu" mixed)
		(14 "In6.Cu" power)
		(16 "In7.Cu" mixed)
		(18 "In8.Cu" power)
		(2 "B.Cu" mixed)
		(9 "F.Adhes" user "F.Adhesive")
		(11 "B.Adhes" user "B.Adhesive")
		(13 "F.Paste" user)
		(15 "B.Paste" user)
		(5 "F.SilkS" user "F.Silkscreen")
		(7 "B.SilkS" user "B.Silkscreen")
		(1 "F.Mask" user)
		(3 "B.Mask" user)
		(17 "Dwgs.User" user "User.Drawings")
		(19 "Cmts.User" user "User.Comments")
		(21 "Eco1.User" user "User.Eco1")
		(23 "Eco2.User" user "User.Eco2")
		(25 "Edge.Cuts" user)
		(27 "Margin" user)
		(31 "F.CrtYd" user "F.Courtyard")
		(29 "B.CrtYd" user "B.Courtyard")
		(35 "F.Fab" user)
		(33 "B.Fab" user)
	)
	(footprint "antmicro-footprints:C_0402_1005Metric"
		(layer "B.Cu")
		(at 206 144.5)
		(descr "Capacitor SMD 0402")
		(tags "capacitor SMD 0402")
		(property "Reference" "C11"
			(at 1.125 -0.45 180)
			(layer "B.SilkS")
			(effects
				(font
					(size 0.7 0.7)
					(thickness 0.15)
				)
				(justify left bottom mirror)
			)
		)
		(property "Value" "C_100n_0402"
			(at 0 -1.169 180)
			(layer "B.Fab")
			(effects
				(font
					(size 0.7 0.7)
					(thickness 0.15)
				)
				(justify left bottom mirror)
			)
		)
		(property "Description" "SMD Multilayer Ceramic Capacitor, 0.1 µF, 50 V, 0402 [1005 Metric], ± 10%, X5R, GRM Series"
			(at 0 0 0)
			(layer "F.Fab")
			(hide yes)
			(effects
				(font
					(size 1.27 1.27)
					(thickness 0.15)
				)
			)
		)
		(property "Author" "Antmicro"
			(at 0 0 0)
			(layer "B.Fab")
			(hide yes)
			(effects
				(font
					(size 1 1)
					(thickness 0.15)
				)
				(justify mirror)
			)
		)
		(property "Dielectric" "X5R"
			(at 0 0 0)
			(layer "B.Fab")
			(hide yes)
			(effects
				(font
					(size 1 1)
					(thickness 0.15)
				)
				(justify mirror)
			)
		)
		(property "License" "Apache-2.0"
			(at 0 0 0)
			(layer "B.Fab")
			(hide yes)
			(effects
				(font
					(size 1 1)
					(thickness 0.15)
				)
				(justify mirror)
			)
		)
		(property "MPN" "GRM155R61H104KE14D"
			(at 0 0 0)
			(layer "B.Fab")
			(hide yes)
			(effects
				(font
					(size 1 1)
					(thickness 0.15)
				)
				(justify mirror)
			)
		)
		(property "Manufacturer" "Murata"
			(at 0 0 0)
			(layer "B.Fab")
			(hide yes)
			(effects
				(font
					(size 1 1)
					(thickness 0.15)
				)
				(justify mirror)
			)
		)
		(property "Val" "100n"
			(at 0 0 0)
			(layer "B.Fab")
			(hide yes)
			(effects
				(font
					(size 1 1)
					(thickness 0.15)
				)
				(justify mirror)
			)
		)
		(property "Voltage" "50V"
			(at 0 0 0)
			(layer "B.Fab")
			(hide yes)
			(effects
				(font
					(size 1 1)
					(thickness 0.15)
				)
				(justify mirror)
			)
		)
		(sheetname "FPGA Bank 12 & 13")
		(sheetfile "fpga-bank-12-13.kicad_sch")
		(attr smd)
		(fp_rect
			(start -0.925 0.47)
			(end 0.925 -0.47)
			(stroke
				(width 0.05)
				(type default)
			)
			(fill no)
			(layer "B.CrtYd")
		)
		(fp_line
			(start -0.494 -0.248)
			(end -0.494 0.25)
			(stroke
				(width 0.15)
				(type solid)
			)
			(layer "B.Fab")
		)
		(fp_line
			(start -0.494 0.25)
			(end 0.504 0.25)
			(stroke
				(width 0.15)
				(type solid)
			)
			(layer "B.Fab")
		)
		(fp_line
			(start 0.504 -0.248)
			(end -0.494 -0.248)
			(stroke
				(width 0.15)
				(type solid)
			)
			(layer "B.Fab")
		)
		(fp_line
			(start 0.504 0.25)
			(end 0.504 -0.248)
			(stroke
				(width 0.15)
				(type solid)
			)
			(layer "B.Fab")
		)
		(pad "1" smd roundrect
			(at -0.48 0)
			(size 0.59 0.64)
			(layers "B.Cu" "B.Mask" "B.Paste")
			(roundrect_rratio 0.25)
			(net 1 "GND")
			(pintype "passive")
		)
		(pad "2" smd roundrect
			(at 0.48 0)
			(size 0.59 0.64)
			(layers "B.Cu" "B.Mask" "B.Paste")
			(roundrect_rratio 0.25)
			(net 24 "+3V3")
			(pintype "passive")
		)
	)
	(footprint "antmicro-footprints:NetTie-2_SMD_Pad0.127mm"
		(layer "B.Cu")
		(at 251.701 127.2 90)
		(descr "Net tie, 2 pin, 0.127mm  SMD pads")
		(tags "net tie")
		(property "Reference" "NT19"
			(at -0.128 1.345 270)
			(layer "B.SilkS")
			(hide yes)
			(effects
				(font
					(size 0.7 0.7)
					(thickness 0.15)
				)
				(justify left bottom mirror)
			)
		)
		(property "Value" "Net-Tie_2"
			(at 0 -1.199 270)
			(layer "B.Fab")
			(effects
				(font
					(size 0.7 0.7)
					(thickness 0.15)
				)
				(justify left bottom mirror)
			)
		)
		(property "Description" "Net tie, 2 pins"
			(at 0 0 90)
			(layer "F.Fab")
			(hide yes)
			(effects
				(font
					(size 1.27 1.27)
					(thickness 0.15)
				)
			)
		)
		(property "Author" "Antmicro"
			(at 378.901 -124.501 0)
			(layer "B.Fab")
			(hide yes)
			(effects
				(font
					(size 1 1)
					(thickness 0.15)
				)
				(justify mirror)
			)
		)
		(property "License" "Apache-2.0"
			(at 378.901 -124.501 0)
			(layer "B.Fab")
			(hide yes)
			(effects
				(font
					(size 1 1)
					(thickness 0.15)
				)
				(justify mirror)
			)
		)
		(property "MPN" ""
			(at 378.901 -124.501 0)
			(layer "B.Fab")
			(hide yes)
			(effects
				(font
					(size 1 1)
					(thickness 0.15)
				)
				(justify mirror)
			)
		)
		(property "Manufacturer" ""
			(at 378.901 -124.501 0)
			(layer "B.Fab")
			(hide yes)
			(effects
				(font
					(size 1 1)
					(thickness 0.15)
				)
				(justify mirror)
			)
		)
		(sheetname "FPGA Config")
		(sheetfile "fpga-config.kicad_sch")
		(attr exclude_from_pos_files)
		(net_tie_pad_groups "1, 2")
		(fp_poly
			(pts
				(xy -0.0635 0.0635) (xy 0.0625 0.0635) (xy 0.0625 -0.0635) (xy -0.0635 -0.0635)
			)
			(stroke
				(width 0)
				(type solid)
			)
			(fill yes)
			(layer "B.Cu")
		)
		(pad "1" smd roundrect
			(at -0.127 0 270)
			(size 0.127 0.127)
			(layers "B.Cu")
			(roundrect_rratio 0.5)
			(chamfer_ratio 0)
			(chamfer top_left bottom_left)
			(net 1332 "/SUP_MCU.CCLK")
			(pinfunction "1")
			(pintype "passive")
		)
		(pad "2" smd roundrect
			(at 0.126 0 90)
			(size 0.127 0.127)
			(layers "B.Cu")
			(roundrect_rratio 0.5)
			(chamfer_ratio 0)
			(chamfer top_left bottom_left)
			(net 56 "/FPGA Bank 14 & 15/SYSTEM_FLASH.CLK")
			(pinfunction "2")
			(pintype "passive")
		)
	)
	(footprint "antmicro-footprints:C_0402_1005Metric"
		(layer "B.Cu")
		(at 213 140.5 180)
		(descr "Capacitor SMD 0402")
		(tags "capacitor SMD 0402")
		(property "Reference" "C24"
			(at -1.1 0.475 0)
			(layer "B.SilkS")
			(effects
				(font
					(size 0.7 0.7)
					(thickness 0.15)
				)
				(justify left bottom mirror)
			)
		)
		(property "Value" "C_100n_0402"
			(at 0 -1.169 0)
			(layer "B.Fab")
			(effects
				(font
					(size 0.7 0.7)
					(thickness 0.15)
				)
				(justify left bottom mirror)
			)
		)
		(property "Description" "SMD Multilayer Ceramic Capacitor, 0.1 µF, 50 V, 0402 [1005 Metric], ± 10%, X5R, GRM Series"
			(at 0 0 180)
			(layer "F.Fab")
			(hide yes)
			(effects
				(font
					(size 1.27 1.27)
					(thickness 0.15)
				)
			)
		)
		(property "Author" "Antmicro"
			(at 426 281 0)
			(layer "B.Fab")
			(hide yes)
			(effects
				(font
					(size 1 1)
					(thickness 0.15)
				)
				(justify mirror)
			)
		)
		(property "Dielectric" "X5R"
			(at 426 281 0)
			(layer "B.Fab")
			(hide yes)
			(effects
				(font
					(size 1 1)
					(thickness 0.15)
				)
				(justify mirror)
			)
		)
		(property "License" "Apache-2.0"
			(at 426 281 0)
			(layer "B.Fab")
			(hide yes)
			(effects
				(font
					(size 1 1)
					(thickness 0.15)
				)
				(justify mirror)
			)
		)
		(property "MPN" "GRM155R61H104KE14D"
			(at 426 281 0)
			(layer "B.Fab")
			(hide yes)
			(effects
				(font
					(size 1 1)
					(thickness 0.15)
				)
				(justify mirror)
			)
		)
		(property "Manufacturer" "Murata"
			(at 426 281 0)
			(layer "B.Fab")
			(hide yes)
			(effects
				(font
					(size 1 1)
					(thickness 0.15)
				)
				(justify mirror)
			)
		)
		(property "Val" "100n"
			(at 426 281 0)
			(layer "B.Fab")
			(hide yes)
			(effects
				(font
					(size 1 1)
					(thickness 0.15)
				)
				(justify mirror)
			)
		)
		(property "Voltage" "50V"
			(at 426 281 0)
			(layer "B.Fab")
			(hide yes)
			(effects
				(font
					(size 1 1)
					(thickness 0.15)
				)
				(justify mirror)
			)
		)
		(sheetname "FPGA Bank 12 & 13")
		(sheetfile "fpga-bank-12-13.kicad_sch")
		(attr smd)
		(fp_rect
			(start -0.925 0.47)
			(end 0.925 -0.47)
			(stroke
				(width 0.05)
				(type default)
			)
			(fill no)
			(layer "B.CrtYd")
		)
		(fp_line
			(start 0.504 0.25)
			(end 0.504 -0.248)
			(stroke
				(width 0.15)
				(type solid)
			)
			(layer "B.Fab")
		)
		(fp_line
			(start 0.504 -0.248)
			(end -0.494 -0.248)
			(stroke
				(width 0.15)
				(type solid)
			)
			(layer "B.Fab")
		)
		(fp_line
			(start -0.494 0.25)
			(end 0.504 0.25)
			(stroke
				(width 0.15)
				(type solid)
			)
			(layer "B.Fab")
		)
		(fp_line
			(start -0.494 -0.248)
			(end -0.494 0.25)
			(stroke
				(width 0.15)
				(type solid)
			)
			(layer "B.Fab")
		)
		(pad "1" smd roundrect
			(at -0.48 0 180)
			(size 0.59 0.64)
			(layers "B.Cu" "B.Mask" "B.Paste")
			(roundrect_rratio 0.25)
			(net 1 "GND")
			(pintype "passive")
		)
		(pad "2" smd roundrect
			(at 0.48 0 180)
			(size 0.59 0.64)
			(layers "B.Cu" "B.Mask" "B.Paste")
			(roundrect_rratio 0.25)
			(net 24 "+3V3")
			(pintype "passive")
		)
	)
	(footprint "antmicro-footprints:NetTie-2_SMD_Pad0.127mm"
		(layer "B.Cu")
		(at 190.09 112.64)
		(descr "Net tie, 2 pin, 0.127mm  SMD pads")
		(tags "net tie")
		(property "Reference" "NT33"
			(at -0.128 1.345 180)
			(layer "B.SilkS")
			(hide yes)
			(effects
				(font
					(size 0.7 0.7)
					(thickness 0.15)
				)
				(justify left bottom mirror)
			)
		)
		(property "Value" "Net-Tie_2"
			(at 0 -1.199 180)
			(layer "B.Fab")
			(effects
				(font
					(size 0.7 0.7)
					(thickness 0.15)
				)
				(justify left bottom mirror)
			)
		)
		(property "Description" "Net tie, 2 pins"
			(at 0 0 0)
			(layer "F.Fab")
			(hide yes)
			(effects
				(font
					(size 1.27 1.27)
					(thickness 0.15)
				)
			)
		)
		(property "Author" "Antmicro"
			(at 0 0 0)
			(layer "B.Fab")
			(hide yes)
			(effects
				(font
					(size 1 1)
					(thickness 0.15)
				)
				(justify mirror)
			)
		)
		(property "License" "Apache-2.0"
			(at 0 0 0)
			(layer "B.Fab")
			(hide yes)
			(effects
				(font
					(size 1 1)
					(thickness 0.15)
				)
				(justify mirror)
			)
		)
		(property "MPN" ""
			(at 0 0 0)
			(layer "B.Fab")
			(hide yes)
			(effects
				(font
					(size 1 1)
					(thickness 0.15)
				)
				(justify mirror)
			)
		)
		(property "Manufacturer" ""
			(at 0 0 0)
			(layer "B.Fab")
			(hide yes)
			(effects
				(font
					(size 1 1)
					(thickness 0.15)
				)
				(justify mirror)
			)
		)
		(sheetname "DC-DC Converters")
		(sheetfile "dc-dc.kicad_sch")
		(attr exclude_from_pos_files)
		(net_tie_pad_groups "1, 2")
		(fp_poly
			(pts
				(xy -0.0635 0.0635) (xy 0.0625 0.0635) (xy 0.0625 -0.0635) (xy -0.0635 -0.0635)
			)
			(stroke
				(width 0)
				(type solid)
			)
			(fill yes)
			(layer "B.Cu")
		)
		(pad "1" smd roundrect
			(at -0.127 0 180)
			(size 0.127 0.127)
			(layers "B.Cu")
			(roundrect_rratio 0.5)
			(chamfer_ratio 0)
			(chamfer top_left bottom_left)
			(net 1221 "/DC-DC Converters/SENSE_1V0_P")
			(pinfunction "1")
			(pintype "passive")
		)
		(pad "2" smd roundrect
			(at 0.126 0)
			(size 0.127 0.127)
			(layers "B.Cu")
			(roundrect_rratio 0.5)
			(chamfer_ratio 0)
			(chamfer top_left bottom_left)
			(net 6 "+1V0_MGTAVCC")
			(pinfunction "2")
			(pintype "passive")
		)
	)
	(footprint "antmicro-footprints:C_0402_1005Metric"
		(layer "B.Cu")
		(at 244.701 158)
		(descr "Capacitor SMD 0402")
		(tags "capacitor SMD 0402")
		(property "Reference" "C291"
			(at 1.374 -0.5 180)
			(layer "B.SilkS")
			(effects
				(font
					(size 0.7 0.7)
					(thickness 0.15)
				)
				(justify left bottom mirror)
			)
		)
		(property "Value" "C_100n_0402"
			(at 0 -1.169 180)
			(layer "B.Fab")
			(effects
				(font
					(size 0.7 0.7)
					(thickness 0.15)
				)
				(justify left bottom mirror)
			)
		)
		(property "Description" "SMD Multilayer Ceramic Capacitor, 0.1 µF, 50 V, 0402 [1005 Metric], ± 10%, X5R, GRM Series"
			(at 0 0 0)
			(layer "F.Fab")
			(hide yes)
			(effects
				(font
					(size 1.27 1.27)
					(thickness 0.15)
				)
			)
		)
		(property "Author" "Antmicro"
			(at 0 0 0)
			(layer "B.Fab")
			(hide yes)
			(effects
				(font
					(size 1 1)
					(thickness 0.15)
				)
				(justify mirror)
			)
		)
		(property "Dielectric" "X5R"
			(at 0 0 0)
			(layer "B.Fab")
			(hide yes)
			(effects
				(font
					(size 1 1)
					(thickness 0.15)
				)
				(justify mirror)
			)
		)
		(property "License" "Apache-2.0"
			(at 0 0 0)
			(layer "B.Fab")
			(hide yes)
			(effects
				(font
					(size 1 1)
					(thickness 0.15)
				)
				(justify mirror)
			)
		)
		(property "MPN" "GRM155R61H104KE14D"
			(at 0 0 0)
			(layer "B.Fab")
			(hide yes)
			(effects
				(font
					(size 1 1)
					(thickness 0.15)
				)
				(justify mirror)
			)
		)
		(property "Manufacturer" "Murata"
			(at 0 0 0)
			(layer "B.Fab")
			(hide yes)
			(effects
				(font
					(size 1 1)
					(thickness 0.15)
				)
				(justify mirror)
			)
		)
		(property "Val" "100n"
			(at 0 0 0)
			(layer "B.Fab")
			(hide yes)
			(effects
				(font
					(size 1 1)
					(thickness 0.15)
				)
				(justify mirror)
			)
		)
		(property "Voltage" "50V"
			(at 0 0 0)
			(layer "B.Fab")
			(hide yes)
			(effects
				(font
					(size 1 1)
					(thickness 0.15)
				)
				(justify mirror)
			)
		)
		(sheetname "HDMI + Ethernet")
		(sheetfile "hdmi-ethernet.kicad_sch")
		(attr smd)
		(fp_rect
			(start -0.925 0.47)
			(end 0.925 -0.47)
			(stroke
				(width 0.05)
				(type default)
			)
			(fill no)
			(layer "B.CrtYd")
		)
		(fp_line
			(start -0.494 -0.248)
			(end -0.494 0.25)
			(stroke
				(width 0.15)
				(type solid)
			)
			(layer "B.Fab")
		)
		(fp_line
			(start -0.494 0.25)
			(end 0.504 0.25)
			(stroke
				(width 0.15)
				(type solid)
			)
			(layer "B.Fab")
		)
		(fp_line
			(start 0.504 -0.248)
			(end -0.494 -0.248)
			(stroke
				(width 0.15)
				(type solid)
			)
			(layer "B.Fab")
		)
		(fp_line
			(start 0.504 0.25)
			(end 0.504 -0.248)
			(stroke
				(width 0.15)
				(type solid)
			)
			(layer "B.Fab")
		)
		(pad "1" smd roundrect
			(at -0.48 0)
			(size 0.59 0.64)
			(layers "B.Cu" "B.Mask" "B.Paste")
			(roundrect_rratio 0.25)
			(net 1 "GND")
			(pintype "passive")
		)
		(pad "2" smd roundrect
			(at 0.48 0)
			(size 0.59 0.64)
			(layers "B.Cu" "B.Mask" "B.Paste")
			(roundrect_rratio 0.25)
			(net 730 "/HDMI + Ethernet/GBE_CONN_COMM")
			(pintype "passive")
		)
	)
	(footprint "antmicro-footprints:C_0402_1005Metric"
		(layer "B.Cu")
		(at 198.325 125.825)
		(descr "Capacitor SMD 0402")
		(tags "capacitor SMD 0402")
		(property "Reference" "C121"
			(at 26.275 -29.375 180)
			(layer "B.SilkS")
			(effects
				(font
					(size 0.7 0.7)
					(thickness 0.15)
				)
				(justify left bottom mirror)
			)
		)
		(property "Value" "C_100n_0402"
			(at 0 -1.169 180)
			(layer "B.Fab")
			(effects
				(font
					(size 0.7 0.7)
					(thickness 0.15)
				)
				(justify left bottom mirror)
			)
		)
		(property "Description" "SMD Multilayer Ceramic Capacitor, 0.1 µF, 50 V, 0402 [1005 Metric], ± 10%, X5R, GRM Series"
			(at 0 0 0)
			(layer "F.Fab")
			(hide yes)
			(effects
				(font
					(size 1.27 1.27)
					(thickness 0.15)
				)
			)
		)
		(property "Author" "Antmicro"
			(at 0 0 0)
			(layer "B.Fab")
			(hide yes)
			(effects
				(font
					(size 1 1)
					(thickness 0.15)
				)
				(justify mirror)
			)
		)
		(property "Dielectric" "X5R"
			(at 0 0 0)
			(layer "B.Fab")
			(hide yes)
			(effects
				(font
					(size 1 1)
					(thickness 0.15)
				)
				(justify mirror)
			)
		)
		(property "License" "Apache-2.0"
			(at 0 0 0)
			(layer "B.Fab")
			(hide yes)
			(effects
				(font
					(size 1 1)
					(thickness 0.15)
				)
				(justify mirror)
			)
		)
		(property "MPN" "GRM155R61H104KE14D"
			(at 0 0 0)
			(layer "B.Fab")
			(hide yes)
			(effects
				(font
					(size 1 1)
					(thickness 0.15)
				)
				(justify mirror)
			)
		)
		(property "Manufacturer" "Murata"
			(at 0 0 0)
			(layer "B.Fab")
			(hide yes)
			(effects
				(font
					(size 1 1)
					(thickness 0.15)
				)
				(justify mirror)
			)
		)
		(property "Val" "100n"
			(at 0 0 0)
			(layer "B.Fab")
			(hide yes)
			(effects
				(font
					(size 1 1)
					(thickness 0.15)
				)
				(justify mirror)
			)
		)
		(property "Voltage" "50V"
			(at 0 0 0)
			(layer "B.Fab")
			(hide yes)
			(effects
				(font
					(size 1 1)
					(thickness 0.15)
				)
				(justify mirror)
			)
		)
		(sheetname "FPGA supply")
		(sheetfile "fpga-supply.kicad_sch")
		(attr smd)
		(fp_rect
			(start -0.925 0.47)
			(end 0.925 -0.47)
			(stroke
				(width 0.05)
				(type default)
			)
			(fill no)
			(layer "B.CrtYd")
		)
		(fp_line
			(start -0.494 -0.248)
			(end -0.494 0.25)
			(stroke
				(width 0.15)
				(type solid)
			)
			(layer "B.Fab")
		)
		(fp_line
			(start -0.494 0.25)
			(end 0.504 0.25)
			(stroke
				(width 0.15)
				(type solid)
			)
			(layer "B.Fab")
		)
		(fp_line
			(start 0.504 -0.248)
			(end -0.494 -0.248)
			(stroke
				(width 0.15)
				(type solid)
			)
			(layer "B.Fab")
		)
		(fp_line
			(start 0.504 0.25)
			(end 0.504 -0.248)
			(stroke
				(width 0.15)
				(type solid)
			)
			(layer "B.Fab")
		)
		(pad "1" smd roundrect
			(at -0.48 0)
			(size 0.59 0.64)
			(layers "B.Cu" "B.Mask" "B.Paste")
			(roundrect_rratio 0.25)
			(net 1 "GND")
			(pintype "passive")
		)
		(pad "2" smd roundrect
			(at 0.48 0)
			(size 0.59 0.64)
			(layers "B.Cu" "B.Mask" "B.Paste")
			(roundrect_rratio 0.25)
			(net 650 "+1V0")
			(pintype "passive")
		)
	)
)
